# S9S_MB_2U (Grand Teton) — schematic netlist excerpt (pin names and nets, part order shuffled) for the footprints in the layout excerpt that follows; sources: Cadence DE-HDL packaged netlist, KiCad conversion of 03242023_DA0F0TMBIJ0_F0T_Motherboard_J_brd_V01_OCP.brd

R4540  Q_RES  33.2 1% CHIP  pkg 0402LF  page 237 : A = SMB_HOST_CLK_BUF_ISO_3V3AUX_S_1 ; B = SMB_HOST_CLK_BUF_ISO_3V3AUX_SCL
R4075  Q_RES  0 5% CHIP  pkg 0402LF  page 212 : A = CLK_GEN2_BMC_RC_OE_N ; B = CLK_GEN2_BMC_RC_OE_R3_N

(kicad_pcb
	(version 20260206)
	(generator "pcbnew")
	(generator_version "10.0")
	(general
		(thickness 1.6)
		(legacy_teardrops no)
	)
	(paper "A4")
	(title_block
		(title "03242023_DA0F0TMBIJ0_F0T_Motherboard_J_brd_V01_OCP.brd")
		(comment 1 "Grand Teton / footprints 1482-1483 of 6105")
	)
	(layers
		(0 "F.Cu" signal "TOP")
		(4 "In1.Cu" signal "GND")
		(6 "In2.Cu" signal "IN1")
		(8 "In3.Cu" signal "GND1")
		(10 "In4.Cu" signal "IN2")
		(12 "In5.Cu" signal "GND2")
		(14 "In6.Cu" signal "IN3")
		(16 "In7.Cu" signal "GND3")
		(18 "In8.Cu" signal "VCC")
		(20 "In9.Cu" signal "VCC1")
		(22 "In10.Cu" signal "GND4")
		(24 "In11.Cu" signal "IN4")
		(26 "In12.Cu" signal "GND5")
		(28 "In13.Cu" signal "IN5")
		(30 "In14.Cu" signal "GND6")
		(32 "In15.Cu" signal "IN6")
		(34 "In16.Cu" signal "GND7")
		(2 "B.Cu" signal "BOTTOM")
		(9 "F.Adhes" user "F.Adhesive")
		(11 "B.Adhes" user "B.Adhesive")
		(13 "F.Paste" user "Package Geometry/Pastemask Top")
		(15 "B.Paste" user "Package Geometry/Pastemask Bottom")
		(5 "F.SilkS" user "Ref Des/Silkscreen Top")
		(7 "B.SilkS" user "Ref Des/Silkscreen Bottom")
		(1 "F.Mask" user "Board Geometry/Soldermask Top")
		(3 "B.Mask" user "Board Geometry/Soldermask Bottom")
		(17 "Dwgs.User" user "User.Drawings")
		(19 "Cmts.User" user "User.Comments")
		(21 "Eco1.User" user "User.Eco1")
		(23 "Eco2.User" user "User.Eco2")
		(25 "Edge.Cuts" user "Board Geometry/Outline")
		(27 "Margin" user)
		(31 "F.CrtYd" user "Package Geometry/Place Bound Top")
		(29 "B.CrtYd" user "Package Geometry/Place Bound Bottom")
		(35 "F.Fab" user "Ref Des/Assembly Top")
		(33 "B.Fab" user "Ref Des/Assembly Bottom")
	)
	(footprint ""
		(layer "F.Cu")
		(at 234.11688 -256.123948 -90)
		(property "Reference" "R4075"
			(at 0 0 270)
			(layer "F.SilkS")
			(hide yes)
			(effects
				(font
					(size 1.27 1.27)
				)
			)
		)
		(property "Value" ""
			(at 0 0 270)
			(layer "F.Fab")
			(effects
				(font
					(size 1.27 1.27)
				)
			)
		)
		(duplicate_pad_numbers_are_jumpers no)
		(fp_line
			(start -0.7874 0.4064)
			(end -0.7874 -0.4064)
			(stroke
				(width 0.1524)
				(type default)
			)
			(layer "F.SilkS")
		)
		(fp_line
			(start 0.7874 0.4064)
			(end -0.7874 0.4064)
			(stroke
				(width 0.1524)
				(type default)
			)
			(layer "F.SilkS")
		)
		(fp_line
			(start -0.7874 -0.4064)
			(end 0.7874 -0.4064)
			(stroke
				(width 0.1524)
				(type default)
			)
			(layer "F.SilkS")
		)
		(fp_line
			(start 0.7874 -0.4064)
			(end 0.7874 0.4064)
			(stroke
				(width 0.1524)
				(type default)
			)
			(layer "F.SilkS")
		)
		(fp_line
			(start -0.67945 0.3048)
			(end -0.67945 -0.305054)
			(stroke
				(width 0.1)
				(type default)
			)
			(layer "F.Fab")
		)
		(fp_line
			(start -0.12065 0.3048)
			(end -0.67945 0.3048)
			(stroke
				(width 0.1)
				(type default)
			)
			(layer "F.Fab")
		)
		(fp_line
			(start 0.120396 0.3048)
			(end 0.120396 0.2794)
			(stroke
				(width 0.1)
				(type default)
			)
			(layer "F.Fab")
		)
		(fp_line
			(start 0.67945 0.3048)
			(end 0.120396 0.3048)
			(stroke
				(width 0.1)
				(type default)
			)
			(layer "F.Fab")
		)
		(fp_line
			(start -0.12065 0.2794)
			(end -0.12065 0.3048)
			(stroke
				(width 0.1)
				(type default)
			)
			(layer "F.Fab")
		)
		(fp_line
			(start 0.120396 0.2794)
			(end -0.12065 0.2794)
			(stroke
				(width 0.1)
				(type default)
			)
			(layer "F.Fab")
		)
		(fp_line
			(start -0.12065 -0.2794)
			(end 0.12065 -0.2794)
			(stroke
				(width 0.1)
				(type default)
			)
			(layer "F.Fab")
		)
		(fp_line
			(start 0.12065 -0.2794)
			(end 0.12065 -0.3048)
			(stroke
				(width 0.1)
				(type default)
			)
			(layer "F.Fab")
		)
		(fp_line
			(start 0.12065 -0.3048)
			(end 0.67945 -0.3048)
			(stroke
				(width 0.1)
				(type default)
			)
			(layer "F.Fab")
		)
		(fp_line
			(start 0.67945 -0.3048)
			(end 0.67945 0.3048)
			(stroke
				(width 0.1)
				(type default)
			)
			(layer "F.Fab")
		)
		(fp_line
			(start -0.67945 -0.305054)
			(end -0.12065 -0.305054)
			(stroke
				(width 0.1)
				(type default)
			)
			(layer "F.Fab")
		)
		(fp_line
			(start -0.12065 -0.305054)
			(end -0.12065 -0.2794)
			(stroke
				(width 0.1)
				(type default)
			)
			(layer "F.Fab")
		)
		(pad "1" smd circle
			(at -0.40005 0 270)
			(size 0 0)
			(layers "F.Cu" "F.Mask" "F.Paste")
			(net "CLK_GEN2_BMC_RC_OE_N")
		)
		(pad "2" smd circle
			(at 0.40005 0 270)
			(size 0 0)
			(layers "F.Cu" "F.Mask" "F.Paste")
			(net "CLK_GEN2_BMC_RC_OE_R3_N")
		)
	)
	(footprint ""
		(layer "F.Cu")
		(at 263.65962 -130.602228 180)
		(property "Reference" "R4540"
			(at 0 0 180)
			(layer "F.SilkS")
			(hide yes)
			(effects
				(font
					(size 1.27 1.27)
				)
			)
		)
		(property "Value" ""
			(at 0 0 180)
			(layer "F.Fab")
			(effects
				(font
					(size 1.27 1.27)
				)
			)
		)
		(duplicate_pad_numbers_are_jumpers no)
		(fp_line
			(start 0.7874 0.4064)
			(end -0.7874 0.4064)
			(stroke
				(width 0.1524)
				(type default)
			)
			(layer "F.SilkS")
		)
		(fp_line
			(start 0.7874 -0.4064)
			(end 0.7874 0.4064)
			(stroke
				(width 0.1524)
				(type default)
			)
			(layer "F.SilkS")
		)
		(fp_line
			(start -0.7874 0.4064)
			(end -0.7874 -0.4064)
			(stroke
				(width 0.1524)
				(type default)
			)
			(layer "F.SilkS")
		)
		(fp_line
			(start -0.7874 -0.4064)
			(end 0.7874 -0.4064)
			(stroke
				(width 0.1524)
				(type default)
			)
			(layer "F.SilkS")
		)
		(fp_line
			(start 0.67945 0.3048)
			(end 0.120396 0.3048)
			(stroke
				(width 0.1)
				(type default)
			)
			(layer "F.Fab")
		)
		(fp_line
			(start 0.67945 -0.3048)
			(end 0.67945 0.3048)
			(stroke
				(width 0.1)
				(type default)
			)
			(layer "F.Fab")
		)
		(fp_line
			(start 0.12065 -0.2794)
			(end 0.12065 -0.3048)
			(stroke
				(width 0.1)
				(type default)
			)
			(layer "F.Fab")
		)
		(fp_line
			(start 0.12065 -0.3048)
			(end 0.67945 -0.3048)
			(stroke
				(width 0.1)
				(type default)
			)
			(layer "F.Fab")
		)
		(fp_line
			(start 0.120396 0.3048)
			(end 0.120396 0.2794)
			(stroke
				(width 0.1)
				(type default)
			)
			(layer "F.Fab")
		)
		(fp_line
			(start 0.120396 0.2794)
			(end -0.12065 0.2794)
			(stroke
				(width 0.1)
				(type default)
			)
			(layer "F.Fab")
		)
		(fp_line
			(start -0.12065 0.3048)
			(end -0.67945 0.3048)
			(stroke
				(width 0.1)
				(type default)
			)
			(layer "F.Fab")
		)
		(fp_line
			(start -0.12065 0.2794)
			(end -0.12065 0.3048)
			(stroke
				(width 0.1)
				(type default)
			)
			(layer "F.Fab")
		)
		(fp_line
			(start -0.12065 -0.2794)
			(end 0.12065 -0.2794)
			(stroke
				(width 0.1)
				(type default)
			)
			(layer "F.Fab")
		)
		(fp_line
			(start -0.12065 -0.305054)
			(end -0.12065 -0.2794)
			(stroke
				(width 0.1)
				(type default)
			)
			(layer "F.Fab")
		)
		(fp_line
			(start -0.67945 0.3048)
			(end -0.67945 -0.305054)
			(stroke
				(width 0.1)
				(type default)
			)
			(layer "F.Fab")
		)
		(fp_line
			(start -0.67945 -0.305054)
			(end -0.12065 -0.305054)
			(stroke
				(width 0.1)
				(type default)
			)
			(layer "F.Fab")
		)
		(pad "1" smd circle
			(at -0.40005 0 180)
			(size 0 0)
			(layers "F.Cu" "F.Mask" "F.Paste")
			(net "SMB_HOST_CLK_BUF_ISO_3V3AUX_S_1")
		)
		(pad "2" smd circle
			(at 0.40005 0 180)
			(size 0 0)
			(layers "F.Cu" "F.Mask" "F.Paste")
			(net "SMB_HOST_CLK_BUF_ISO_3V3AUX_SCL")
		)
	)
)
